(kicad_pcb
	(version 20260206)
	(generator "pcbnew")
	(generator_version "10.0")
	(general
		(thickness 1.6)
		(legacy_teardrops no)
	)
	(paper "A4")
	(title_block
		(title "03242023_DA0F0TMBIJ0_F0T_Motherboard_J_brd_V01_OCP.brd")
		(comment 1 "Grand Teton / footprint 3039 of 6105 (U2), pads 1493-1601 of 4677")
	)
	(layers
		(0 "F.Cu" signal "TOP")
		(4 "In1.Cu" signal "GND")
		(6 "In2.Cu" signal "IN1")
		(8 "In3.Cu" signal "GND1")
		(10 "In4.Cu" signal "IN2")
		(12 "In5.Cu" signal "GND2")
		(14 "In6.Cu" signal "IN3")
		(16 "In7.Cu" signal "GND3")
		(18 "In8.Cu" signal "VCC")
		(20 "In9.Cu" signal "VCC1")
		(22 "In10.Cu" signal "GND4")
		(24 "In11.Cu" signal "IN4")
		(26 "In12.Cu" signal "GND5")
		(28 "In13.Cu" signal "IN5")
		(30 "In14.Cu" signal "GND6")
		(32 "In15.Cu" signal "IN6")
		(34 "In16.Cu" signal "GND7")
		(2 "B.Cu" signal "BOTTOM")
		(9 "F.Adhes" user "F.Adhesive")
		(11 "B.Adhes" user "B.Adhesive")
		(13 "F.Paste" user "Package Geometry/Pastemask Top")
		(15 "B.Paste" user "Package Geometry/Pastemask Bottom")
		(5 "F.SilkS" user "Ref Des/Silkscreen Top")
		(7 "B.SilkS" user "Ref Des/Silkscreen Bottom")
		(1 "F.Mask" user "Board Geometry/Soldermask Top")
		(3 "B.Mask" user "Board Geometry/Soldermask Bottom")
		(17 "Dwgs.User" user "User.Drawings")
		(19 "Cmts.User" user "User.Comments")
		(21 "Eco1.User" user "User.Eco1")
		(23 "Eco2.User" user "User.Eco2")
		(25 "Edge.Cuts" user "Board Geometry/Outline")
		(27 "Margin" user)
		(31 "F.CrtYd" user "Package Geometry/Place Bound Top")
		(29 "B.CrtYd" user "Package Geometry/Place Bound Bottom")
		(35 "F.Fab" user "Ref Des/Assembly Top")
		(33 "B.Fab" user "Ref Des/Assembly Bottom")
	)
	(footprint ""
		(layer "F.Cu")
		(at 359.870248 -251.76988 90)
		(property "Reference" "U2"
			(at -74.416158 -44.488608 0)
			(unlocked yes)
			(layer "F.SilkS")
			(effects
				(font
					(size 1.6002 1.1938)
					(thickness 0.1524)
				)
				(justify left)
			)
		)
		(property "Value" ""
			(at 0 0 90)
			(layer "F.Fab")
			(effects
				(font
					(size 1.27 1.27)
				)
			)
		)
		(duplicate_pad_numbers_are_jumpers no)
		(pad "BU72" smd circle
			(at 21.961094 -0.649732 270)
			(size 0.4318 0.4318)
			(layers "F.Cu" "F.Mask" "F.Paste")
			(net "PVCCIN_CPU0")
		)
		(pad "BU74" smd circle
			(at 23.58898 -0.649732 270)
			(size 0.4318 0.4318)
			(layers "F.Cu" "F.Mask" "F.Paste")
			(net "PVCCIN_CPU0")
		)
		(pad "BU76" smd circle
			(at 25.216612 -0.649732 270)
			(size 0.4318 0.4318)
			(layers "F.Cu" "F.Mask" "F.Paste")
			(net "PVCCIN_CPU0")
		)
		(pad "BU78" smd circle
			(at 26.844498 -0.649732 270)
			(size 0.4318 0.4318)
			(layers "F.Cu" "F.Mask" "F.Paste")
			(net "PVCCIN_CPU0")
		)
		(pad "BU80" smd circle
			(at 28.472384 -0.649732 270)
			(size 0.4318 0.4318)
			(layers "F.Cu" "F.Mask" "F.Paste")
			(net "PVCCIN_CPU0")
		)
		(pad "BU82" smd circle
			(at 30.100016 -0.649732 270)
			(size 0.4318 0.4318)
			(layers "F.Cu" "F.Mask" "F.Paste")
			(net "PVCCIN_CPU0")
		)
		(pad "BU84" smd circle
			(at 31.727902 -0.649732 270)
			(size 0.4318 0.4318)
			(layers "F.Cu" "F.Mask" "F.Paste")
			(net "PVCCIN_CPU0")
		)
		(pad "BU86" smd circle
			(at 33.355534 -0.649732 270)
			(size 0.4318 0.4318)
			(layers "F.Cu" "F.Mask" "F.Paste")
			(net "PVCCIN_CPU0")
		)
		(pad "BU88" smd circle
			(at 34.98342 -0.649732 270)
			(size 0.4318 0.4318)
			(layers "F.Cu" "F.Mask" "F.Paste")
			(net "PVCCIN_CPU0")
		)
		(pad "BU90" smd oval
			(at 36.611306 -0.649732)
			(size 0.381 0.4826)
			(drill
				(offset 0 -0.0508)
			)
			(layers "F.Cu" "F.Mask" "F.Paste")
			(net "PVCCIN_CPU0")
		)
		(pad "BV2" smd oval
			(at -36.611306 -0.290068 180)
			(size 0.381 0.4826)
			(drill
				(offset 0 -0.0508)
			)
			(layers "F.Cu" "F.Mask" "F.Paste")
			(net "GND")
		)
		(pad "BV4" smd circle
			(at -34.98342 -0.290068 270)
			(size 0.4318 0.4318)
			(layers "F.Cu" "F.Mask" "F.Paste")
			(net "GND")
		)
		(pad "BV6" smd circle
			(at -33.355534 -0.290068 270)
			(size 0.4318 0.4318)
			(layers "F.Cu" "F.Mask" "F.Paste")
			(net "GND")
		)
		(pad "BV8" smd circle
			(at -31.727902 -0.290068 270)
			(size 0.4318 0.4318)
			(layers "F.Cu" "F.Mask" "F.Paste")
			(net "GND")
		)
		(pad "BV10" smd circle
			(at -30.100016 -0.290068 270)
			(size 0.4318 0.4318)
			(layers "F.Cu" "F.Mask" "F.Paste")
			(net "P5E_CPU0_PE1_RX_DN<8>")
		)
		(pad "BV12" smd circle
			(at -28.472384 -0.290068 270)
			(size 0.4318 0.4318)
			(layers "F.Cu" "F.Mask" "F.Paste")
			(net "GND")
		)
		(pad "BV14" smd circle
			(at -26.844498 -0.290068 270)
			(size 0.4318 0.4318)
			(layers "F.Cu" "F.Mask" "F.Paste")
			(net "P5E_CPU0_PE1_TX_DN<8>")
		)
		(pad "BV16" smd circle
			(at -25.216612 -0.290068 270)
			(size 0.4318 0.4318)
			(layers "F.Cu" "F.Mask" "F.Paste")
			(net "GND")
		)
		(pad "BV18" smd circle
			(at -23.58898 -0.290068 270)
			(size 0.4318 0.4318)
			(layers "F.Cu" "F.Mask" "F.Paste")
			(net "GND")
		)
		(pad "BV20" smd circle
			(at -21.961094 -0.290068 270)
			(size 0.4318 0.4318)
			(layers "F.Cu" "F.Mask" "F.Paste")
			(net "GND")
		)
		(pad "BV22" smd circle
			(at -20.333462 -0.290068 270)
			(size 0.4318 0.4318)
			(layers "F.Cu" "F.Mask" "F.Paste")
			(net "NC_CPU0_UPI1_APROBE<0>")
		)
		(pad "BV24" smd circle
			(at -18.705576 -0.290068 270)
			(size 0.4318 0.4318)
			(layers "F.Cu" "F.Mask" "F.Paste")
			(net "JTAG_DBP_CPU0_GTL_R_TDI")
		)
		(pad "BV26" smd circle
			(at -17.07769 -0.290068 270)
			(size 0.4318 0.4318)
			(layers "F.Cu" "F.Mask" "F.Paste")
			(net "FM_PEHPCPU0_ALERT_N")
		)
		(pad "BV28" smd circle
			(at -15.450058 -0.290068 270)
			(size 0.4318 0.4318)
			(layers "F.Cu" "F.Mask" "F.Paste")
			(net "TP_TRC_CPU0_PTI<7>")
		)
		(pad "BV30" smd circle
			(at -13.822426 -0.290068 270)
			(size 0.4318 0.4318)
			(layers "F.Cu" "F.Mask" "F.Paste")
			(net "TP_TRC_CPU0_PTI<5>")
		)
		(pad "BV32" smd circle
			(at -12.19454 -0.290068 270)
			(size 0.4318 0.4318)
			(layers "F.Cu" "F.Mask" "F.Paste")
			(net "PVCCIN_CPU0")
		)
		(pad "BV34" smd circle
			(at -10.566654 -0.290068 270)
			(size 0.4318 0.4318)
			(layers "F.Cu" "F.Mask" "F.Paste")
			(net "PVCCIN_CPU0")
		)
		(pad "BV36" smd circle
			(at -8.939022 -0.290068 270)
			(size 0.4318 0.4318)
			(layers "F.Cu" "F.Mask" "F.Paste")
			(net "PVCCIN_CPU0")
		)
		(pad "BV38" smd circle
			(at -7.311136 -0.290068 270)
			(size 0.4318 0.4318)
			(layers "F.Cu" "F.Mask" "F.Paste")
			(net "PVCCIN_CPU0")
		)
		(pad "BV40" smd circle
			(at -5.68325 -0.290068 270)
			(size 0.4318 0.4318)
			(layers "F.Cu" "F.Mask" "F.Paste")
			(net "PVCCIN_CPU0")
		)
		(pad "BV42" smd circle
			(at -4.055618 -0.290068 270)
			(size 0.4318 0.4318)
			(layers "F.Cu" "F.Mask" "F.Paste")
			(net "PVCCIN_CPU0")
		)
		(pad "BV44" smd circle
			(at -2.427732 -0.290068 270)
			(size 0.4318 0.4318)
			(layers "F.Cu" "F.Mask" "F.Paste")
			(net "PVCCIN_CPU0")
		)
		(pad "BV47" smd circle
			(at 1.613916 -0.180086 270)
			(size 0.4318 0.4318)
			(layers "F.Cu" "F.Mask" "F.Paste")
			(net "PVCCIN_CPU0")
		)
		(pad "BV49" smd circle
			(at 3.241802 -0.180086 270)
			(size 0.4318 0.4318)
			(layers "F.Cu" "F.Mask" "F.Paste")
			(net "PVCCIN_CPU0")
		)
		(pad "BV51" smd circle
			(at 4.869434 -0.180086 270)
			(size 0.4318 0.4318)
			(layers "F.Cu" "F.Mask" "F.Paste")
			(net "PVCCIN_CPU0")
		)
		(pad "BV53" smd circle
			(at 6.49732 -0.180086 270)
			(size 0.4318 0.4318)
			(layers "F.Cu" "F.Mask" "F.Paste")
			(net "PVCCIN_CPU0")
		)
		(pad "BV55" smd circle
			(at 8.124952 -0.180086 270)
			(size 0.4318 0.4318)
			(layers "F.Cu" "F.Mask" "F.Paste")
			(net "PVCCIN_CPU0")
		)
		(pad "BV57" smd circle
			(at 9.752838 -0.180086 270)
			(size 0.4318 0.4318)
			(layers "F.Cu" "F.Mask" "F.Paste")
			(net "PVCCIN_CPU0")
		)
		(pad "BV59" smd circle
			(at 11.380724 -0.180086 270)
			(size 0.4318 0.4318)
			(layers "F.Cu" "F.Mask" "F.Paste")
			(net "PVCCIN_CPU0")
		)
		(pad "BV61" smd circle
			(at 13.008356 -0.180086 270)
			(size 0.4318 0.4318)
			(layers "F.Cu" "F.Mask" "F.Paste")
			(net "PVCCIN_CPU0")
		)
		(pad "BV63" smd circle
			(at 14.635988 -0.180086 270)
			(size 0.4318 0.4318)
			(layers "F.Cu" "F.Mask" "F.Paste")
			(net "PVCCIN_CPU0")
		)
		(pad "BV65" smd circle
			(at 16.263874 -0.180086 270)
			(size 0.4318 0.4318)
			(layers "F.Cu" "F.Mask" "F.Paste")
			(net "PVCCIN_CPU0")
		)
		(pad "BV67" smd circle
			(at 17.89176 -0.180086 270)
			(size 0.4318 0.4318)
			(layers "F.Cu" "F.Mask" "F.Paste")
			(net "PVCCIN_CPU0")
		)
		(pad "BV69" smd circle
			(at 19.519392 -0.180086 270)
			(size 0.4318 0.4318)
			(layers "F.Cu" "F.Mask" "F.Paste")
			(net "PVCCIN_CPU0")
		)
		(pad "BV71" smd circle
			(at 21.147278 -0.180086 270)
			(size 0.4318 0.4318)
			(layers "F.Cu" "F.Mask" "F.Paste")
			(net "PVCCIN_CPU0")
		)
		(pad "BV73" smd circle
			(at 22.77491 -0.180086 270)
			(size 0.4318 0.4318)
			(layers "F.Cu" "F.Mask" "F.Paste")
			(net "PVCCIN_CPU0")
		)
		(pad "BV75" smd circle
			(at 24.402796 -0.180086 270)
			(size 0.4318 0.4318)
			(layers "F.Cu" "F.Mask" "F.Paste")
			(net "PVCCIN_CPU0")
		)
		(pad "BV77" smd circle
			(at 26.030682 -0.180086 270)
			(size 0.4318 0.4318)
			(layers "F.Cu" "F.Mask" "F.Paste")
			(net "PVCCIN_CPU0")
		)
		(pad "BV79" smd circle
			(at 27.658314 -0.180086 270)
			(size 0.4318 0.4318)
			(layers "F.Cu" "F.Mask" "F.Paste")
			(net "PVCCIN_CPU0")
		)
		(pad "BV81" smd circle
			(at 29.2862 -0.180086 270)
			(size 0.4318 0.4318)
			(layers "F.Cu" "F.Mask" "F.Paste")
			(net "PVCCIN_CPU0")
		)
		(pad "BV83" smd circle
			(at 30.914086 -0.180086 270)
			(size 0.4318 0.4318)
			(layers "F.Cu" "F.Mask" "F.Paste")
			(net "PVCCIN_CPU0")
		)
		(pad "BV85" smd circle
			(at 32.541718 -0.180086 270)
			(size 0.4318 0.4318)
			(layers "F.Cu" "F.Mask" "F.Paste")
			(net "PVCCIN_CPU0")
		)
		(pad "BV87" smd circle
			(at 34.169604 -0.180086 270)
			(size 0.4318 0.4318)
			(layers "F.Cu" "F.Mask" "F.Paste")
			(net "PVCCIN_CPU0")
		)
		(pad "BV89" smd circle
			(at 35.797236 -0.180086 270)
			(size 0.4318 0.4318)
			(layers "F.Cu" "F.Mask" "F.Paste")
			(net "PVCCIN_CPU0")
		)
		(pad "BW3" smd circle
			(at -35.797236 0.180086 270)
			(size 0.4318 0.4318)
			(layers "F.Cu" "F.Mask" "F.Paste")
			(net "GND")
		)
		(pad "BW5" smd circle
			(at -34.169604 0.180086 270)
			(size 0.4318 0.4318)
			(layers "F.Cu" "F.Mask" "F.Paste")
			(net "GND")
		)
		(pad "BW7" smd circle
			(at -32.541718 0.180086 270)
			(size 0.4318 0.4318)
			(layers "F.Cu" "F.Mask" "F.Paste")
			(net "UPI_CPU0_CPU1_P1P0_DN<23>")
		)
		(pad "BW9" smd circle
			(at -30.914086 0.180086 270)
			(size 0.4318 0.4318)
			(layers "F.Cu" "F.Mask" "F.Paste")
			(net "GND")
		)
		(pad "BW11" smd circle
			(at -29.2862 0.180086 270)
			(size 0.4318 0.4318)
			(layers "F.Cu" "F.Mask" "F.Paste")
			(net "P5E_CPU0_PE1_RX_DN<7>")
		)
		(pad "BW13" smd circle
			(at -27.658314 0.180086 270)
			(size 0.4318 0.4318)
			(layers "F.Cu" "F.Mask" "F.Paste")
			(net "GND")
		)
		(pad "BW15" smd circle
			(at -26.030682 0.180086 270)
			(size 0.4318 0.4318)
			(layers "F.Cu" "F.Mask" "F.Paste")
			(net "P5E_CPU0_PE1_TX_DP<8>")
		)
		(pad "BW17" smd circle
			(at -24.402796 0.180086 270)
			(size 0.4318 0.4318)
			(layers "F.Cu" "F.Mask" "F.Paste")
			(net "GND")
		)
		(pad "BW19" smd circle
			(at -22.77491 0.180086 270)
			(size 0.4318 0.4318)
			(layers "F.Cu" "F.Mask" "F.Paste")
			(net "DMI_CPU0_PCH_TX_DP<0>")
		)
		(pad "BW21" smd circle
			(at -21.147278 0.180086 270)
			(size 0.4318 0.4318)
			(layers "F.Cu" "F.Mask" "F.Paste")
			(net "NC_CPU0_DMI_APROBE<1>")
		)
		(pad "BW23" smd circle
			(at -19.519392 0.180086 270)
			(size 0.4318 0.4318)
			(layers "F.Cu" "F.Mask" "F.Paste")
			(net "NC_CPU0_PE2_APROBE<1>")
		)
		(pad "BW25" smd circle
			(at -17.89176 0.180086 270)
			(size 0.4318 0.4318)
			(layers "F.Cu" "F.Mask" "F.Paste")
			(net "JTAG_CPU0_MUX_GTL_TDO")
		)
		(pad "BW27" smd circle
			(at -16.263874 0.180086 270)
			(size 0.4318 0.4318)
			(layers "F.Cu" "F.Mask" "F.Paste")
			(net "GND")
		)
		(pad "BW29" smd circle
			(at -14.635988 0.180086 270)
			(size 0.4318 0.4318)
			(layers "F.Cu" "F.Mask" "F.Paste")
			(net "GND")
		)
		(pad "BW31" smd circle
			(at -13.008356 0.180086 270)
			(size 0.4318 0.4318)
			(layers "F.Cu" "F.Mask" "F.Paste")
			(net "GND")
		)
		(pad "BW33" smd circle
			(at -11.380724 0.180086 270)
			(size 0.4318 0.4318)
			(layers "F.Cu" "F.Mask" "F.Paste")
			(net "PVCCIN_CPU0")
		)
		(pad "BW35" smd circle
			(at -9.752838 0.180086 270)
			(size 0.4318 0.4318)
			(layers "F.Cu" "F.Mask" "F.Paste")
			(net "PVCCIN_CPU0")
		)
		(pad "BW37" smd circle
			(at -8.124952 0.180086 270)
			(size 0.4318 0.4318)
			(layers "F.Cu" "F.Mask" "F.Paste")
			(net "PVCCIN_CPU0")
		)
		(pad "BW39" smd circle
			(at -6.49732 0.180086 270)
			(size 0.4318 0.4318)
			(layers "F.Cu" "F.Mask" "F.Paste")
			(net "PVCCIN_CPU0")
		)
		(pad "BW41" smd circle
			(at -4.869434 0.180086 270)
			(size 0.4318 0.4318)
			(layers "F.Cu" "F.Mask" "F.Paste")
			(net "PVCCIN_CPU0")
		)
		(pad "BW43" smd circle
			(at -3.241802 0.180086 270)
			(size 0.4318 0.4318)
			(layers "F.Cu" "F.Mask" "F.Paste")
			(net "PVCCIN_CPU0")
		)
		(pad "BW45" smd circle
			(at -1.613916 0.180086 270)
			(size 0.4318 0.4318)
			(layers "F.Cu" "F.Mask" "F.Paste")
			(net "PVCCIN_CPU0")
		)
		(pad "BW48" smd circle
			(at 2.427732 0.290068 270)
			(size 0.4318 0.4318)
			(layers "F.Cu" "F.Mask" "F.Paste")
			(net "PVCCIN_CPU0")
		)
		(pad "BW50" smd circle
			(at 4.055618 0.290068 270)
			(size 0.4318 0.4318)
			(layers "F.Cu" "F.Mask" "F.Paste")
			(net "PVCCIN_CPU0")
		)
		(pad "BW52" smd circle
			(at 5.68325 0.290068 270)
			(size 0.4318 0.4318)
			(layers "F.Cu" "F.Mask" "F.Paste")
			(net "PVCCIN_CPU0")
		)
		(pad "BW54" smd circle
			(at 7.311136 0.290068 270)
			(size 0.4318 0.4318)
			(layers "F.Cu" "F.Mask" "F.Paste")
			(net "PVCCIN_CPU0")
		)
		(pad "BW56" smd circle
			(at 8.939022 0.290068 270)
			(size 0.4318 0.4318)
			(layers "F.Cu" "F.Mask" "F.Paste")
			(net "PVCCIN_CPU0")
		)
		(pad "BW58" smd circle
			(at 10.566654 0.290068 270)
			(size 0.4318 0.4318)
			(layers "F.Cu" "F.Mask" "F.Paste")
			(net "PVCCIN_CPU0")
		)
		(pad "BW60" smd circle
			(at 12.19454 0.290068 270)
			(size 0.4318 0.4318)
			(layers "F.Cu" "F.Mask" "F.Paste")
			(net "PVCCIN_CPU0")
		)
		(pad "BW62" smd circle
			(at 13.822426 0.290068 270)
			(size 0.4318 0.4318)
			(layers "F.Cu" "F.Mask" "F.Paste")
			(net "PVCCIN_CPU0")
		)
		(pad "BW64" smd circle
			(at 15.450058 0.290068 270)
			(size 0.4318 0.4318)
			(layers "F.Cu" "F.Mask" "F.Paste")
			(net "PVCCIN_CPU0")
		)
		(pad "BW66" smd circle
			(at 17.07769 0.290068 270)
			(size 0.4318 0.4318)
			(layers "F.Cu" "F.Mask" "F.Paste")
			(net "PVCCIN_CPU0")
		)
		(pad "BW68" smd circle
			(at 18.705576 0.290068 270)
			(size 0.4318 0.4318)
			(layers "F.Cu" "F.Mask" "F.Paste")
			(net "PVCCIN_CPU0")
		)
		(pad "BW70" smd circle
			(at 20.333462 0.290068 270)
			(size 0.4318 0.4318)
			(layers "F.Cu" "F.Mask" "F.Paste")
			(net "PVCCIN_CPU0")
		)
		(pad "BW72" smd circle
			(at 21.961094 0.290068 270)
			(size 0.4318 0.4318)
			(layers "F.Cu" "F.Mask" "F.Paste")
			(net "PVCCIN_CPU0")
		)
		(pad "BW74" smd circle
			(at 23.58898 0.290068 270)
			(size 0.4318 0.4318)
			(layers "F.Cu" "F.Mask" "F.Paste")
			(net "PVCCIN_CPU0")
		)
		(pad "BW76" smd circle
			(at 25.216612 0.290068 270)
			(size 0.4318 0.4318)
			(layers "F.Cu" "F.Mask" "F.Paste")
			(net "PVCCIN_CPU0")
		)
		(pad "BW78" smd circle
			(at 26.844498 0.290068 270)
			(size 0.4318 0.4318)
			(layers "F.Cu" "F.Mask" "F.Paste")
			(net "PVCCIN_CPU0")
		)
		(pad "BW80" smd circle
			(at 28.472384 0.290068 270)
			(size 0.4318 0.4318)
			(layers "F.Cu" "F.Mask" "F.Paste")
			(net "PVCCIN_CPU0")
		)
		(pad "BW82" smd circle
			(at 30.100016 0.290068 270)
			(size 0.4318 0.4318)
			(layers "F.Cu" "F.Mask" "F.Paste")
			(net "PVCCIN_CPU0")
		)
		(pad "BW84" smd circle
			(at 31.727902 0.290068 270)
			(size 0.4318 0.4318)
			(layers "F.Cu" "F.Mask" "F.Paste")
			(net "PVCCIN_CPU0")
		)
		(pad "BW86" smd circle
			(at 33.355534 0.290068 270)
			(size 0.4318 0.4318)
			(layers "F.Cu" "F.Mask" "F.Paste")
			(net "PVCCIN_CPU0")
		)
		(pad "BW88" smd circle
			(at 34.98342 0.290068 270)
			(size 0.4318 0.4318)
			(layers "F.Cu" "F.Mask" "F.Paste")
			(net "PVCCIN_CPU0")
		)
		(pad "BW90" smd oval
			(at 36.611306 0.290068)
			(size 0.381 0.4826)
			(drill
				(offset 0 -0.0508)
			)
			(layers "F.Cu" "F.Mask" "F.Paste")
			(net "PVCCIN_CPU0")
		)
		(pad "BY2" smd oval
			(at -36.611306 0.649732 180)
			(size 0.381 0.4826)
			(drill
				(offset 0 -0.0508)
			)
			(layers "F.Cu" "F.Mask" "F.Paste")
			(net "UPI_CPU1_CPU0_P0P1_DN<23>")
		)
		(pad "BY4" smd circle
			(at -34.98342 0.649732 270)
			(size 0.4318 0.4318)
			(layers "F.Cu" "F.Mask" "F.Paste")
			(net "GND")
		)
		(pad "BY6" smd circle
			(at -33.355534 0.649732 270)
			(size 0.4318 0.4318)
			(layers "F.Cu" "F.Mask" "F.Paste")
			(net "UPI_CPU0_CPU1_P1P0_DP<23>")
		)
		(pad "BY8" smd circle
			(at -31.727902 0.649732 270)
			(size 0.4318 0.4318)
			(layers "F.Cu" "F.Mask" "F.Paste")
			(net "GND")
		)
		(pad "BY10" smd circle
			(at -30.100016 0.649732 270)
			(size 0.4318 0.4318)
			(layers "F.Cu" "F.Mask" "F.Paste")
			(net "P5E_CPU0_PE1_RX_DP<7>")
		)
		(pad "BY12" smd circle
			(at -28.472384 0.649732 270)
			(size 0.4318 0.4318)
			(layers "F.Cu" "F.Mask" "F.Paste")
			(net "GND")
		)
		(pad "BY14" smd circle
			(at -26.844498 0.649732 270)
			(size 0.4318 0.4318)
			(layers "F.Cu" "F.Mask" "F.Paste")
			(net "P5E_CPU0_PE1_TX_DP<7>")
		)
		(pad "BY16" smd circle
			(at -25.216612 0.649732 270)
			(size 0.4318 0.4318)
			(layers "F.Cu" "F.Mask" "F.Paste")
			(net "GND")
		)
		(pad "BY18" smd circle
			(at -23.58898 0.649732 270)
			(size 0.4318 0.4318)
			(layers "F.Cu" "F.Mask" "F.Paste")
			(net "DMI_CPU0_PCH_TX_DN<1>")
		)
		(pad "BY20" smd circle
			(at -21.961094 0.649732 270)
			(size 0.4318 0.4318)
			(layers "F.Cu" "F.Mask" "F.Paste")
			(net "GND")
		)
		(pad "BY22" smd circle
			(at -20.333462 0.649732 270)
			(size 0.4318 0.4318)
			(layers "F.Cu" "F.Mask" "F.Paste")
			(net "I3C_SPD_DDRABCD_CPU0_SDA")
		)
	)
)
